(kicad_pcb
	(version 20260206)
	(generator "pcbnew")
	(generator_version "10.0")
	(general
		(thickness 1.6)
		(legacy_teardrops no)
	)
	(paper "A4")
	(title_block
		(title "pdpb — Lightning_PDPB_BRD.brd")
		(comment 1 "Lightning (Wiwynn / Facebook NVMe JBOF) / footprints 471-477 of 1140")
	)
	(layers
		(0 "F.Cu" signal "TOP")
		(4 "In1.Cu" signal "L2GND")
		(6 "In2.Cu" signal "L3")
		(8 "In3.Cu" signal "L4VCC")
		(10 "In4.Cu" signal "L5VCC")
		(12 "In5.Cu" signal "L6")
		(14 "In6.Cu" signal "L7GND")
		(2 "B.Cu" signal "BOTTOM")
		(9 "F.Adhes" user "F.Adhesive")
		(11 "B.Adhes" user "B.Adhesive")
		(13 "F.Paste" user "Package Geometry/Pastemask Top")
		(15 "B.Paste" user "Package Geometry/Pastemask Bottom")
		(5 "F.SilkS" user "Ref Des/Silkscreen Top")
		(7 "B.SilkS" user "Ref Des/Silkscreen Bottom")
		(1 "F.Mask" user "Board Geometry/Soldermask Top")
		(3 "B.Mask" user "Board Geometry/Soldermask Bottom")
		(17 "Dwgs.User" user "User.Drawings")
		(19 "Cmts.User" user "User.Comments")
		(21 "Eco1.User" user "User.Eco1")
		(23 "Eco2.User" user "User.Eco2")
		(25 "Edge.Cuts" user "Board Geometry/Outline")
		(27 "Margin" user)
		(31 "F.CrtYd" user "Package Geometry/Place Bound Top")
		(29 "B.CrtYd" user "Package Geometry/Place Bound Bottom")
		(35 "F.Fab" user "Ref Des/Assembly Top")
		(33 "B.Fab" user "Ref Des/Assembly Bottom")
	)
	(footprint ""
		(layer "F.Cu")
		(at 247.1928 -360.6038)
		(property "Reference" "C348"
			(at 0 0 0)
			(layer "F.SilkS")
			(hide yes)
			(effects
				(font
					(size 1.27 1.27)
				)
			)
		)
		(property "Value" "SC22U25V6KX-GP-U"
			(at -2.860802 -5.279644 0)
			(unlocked yes)
			(layer "F.Fab")
			(hide yes)
			(effects
				(font
					(size 1.016 1.016)
					(thickness 0.1524)
				)
			)
		)
		(property "Device Type" "C1206-TO0D3H75"
			(at -2.860802 -6.803644 0)
			(unlocked yes)
			(layer "F.Fab")
			(hide yes)
			(effects
				(font
					(size 1.016 1.016)
					(thickness 0.1524)
				)
			)
		)
		(duplicate_pad_numbers_are_jumpers no)
		(fp_line
			(start -1.3081 -2.3749)
			(end 1.3081 -2.3749)
			(stroke
				(width 0.1524)
				(type default)
			)
			(layer "F.SilkS")
		)
		(fp_line
			(start -1.3081 2.3749)
			(end -1.3081 -2.3749)
			(stroke
				(width 0.1524)
				(type default)
			)
			(layer "F.SilkS")
		)
		(fp_line
			(start 1.3081 -2.3749)
			(end 1.3081 2.3749)
			(stroke
				(width 0.1524)
				(type default)
			)
			(layer "F.SilkS")
		)
		(fp_line
			(start 1.3081 2.3749)
			(end -1.3081 2.3749)
			(stroke
				(width 0.1524)
				(type default)
			)
			(layer "F.SilkS")
		)
		(fp_rect
			(start -0.8001 1.6002)
			(end 0.8001 -1.6002)
			(stroke
				(width 0)
				(type default)
			)
			(fill no)
			(layer "F.CrtYd")
		)
		(fp_poly
			(pts
				(xy -1.5621 2.4511) (xy -1.5621 1.6002) (xy 0.8001 1.6002) (xy 0.8001 -1.6002) (xy -0.8001 -1.6002)
				(xy -0.8001 1.5875) (xy -1.5621 1.5875) (xy -1.5621 -2.4511) (xy 1.5621 -2.4511) (xy 1.5621 2.4511)
			)
			(stroke
				(width 0)
				(type default)
			)
			(fill no)
			(layer "F.CrtYd")
		)
		(fp_rect
			(start -1.5621 2.4511)
			(end 1.5621 -2.4511)
			(stroke
				(width 0)
				(type default)
			)
			(fill no)
			(layer "F.Fab")
		)
		(pad "1" smd rect
			(at 0 -1.392936)
			(size 2.1082 1.4478)
			(layers "F.Cu" "F.Mask" "F.Paste")
			(net "P12V")
		)
		(pad "2" smd rect
			(at 0 1.392936)
			(size 2.1082 1.4478)
			(layers "F.Cu" "F.Mask" "F.Paste")
			(net "GND")
		)
	)
	(footprint ""
		(layer "F.Cu")
		(at 83.185 -153.67 -90)
		(property "Reference" "PR9048"
			(at 0 0 270)
			(layer "F.SilkS")
			(hide yes)
			(effects
				(font
					(size 1.27 1.27)
				)
			)
		)
		(property "Value" "0R2J-2-GP"
			(at 0.064008 -3.993896 270)
			(unlocked yes)
			(layer "F.Fab")
			(hide yes)
			(effects
				(font
					(size 1.016 1.016)
					(thickness 0.1524)
				)
			)
		)
		(property "Device Type" "R402H16"
			(at 0.064008 -5.517896 270)
			(unlocked yes)
			(layer "F.Fab")
			(hide yes)
			(effects
				(font
					(size 1.016 1.016)
					(thickness 0.1524)
				)
			)
		)
		(duplicate_pad_numbers_are_jumpers no)
		(fp_line
			(start -0.508 -0.9398)
			(end -0.508 0.9398)
			(stroke
				(width 0.1524)
				(type default)
			)
			(layer "F.SilkS")
		)
		(fp_line
			(start 0.508 -0.9398)
			(end -0.508 -0.9398)
			(stroke
				(width 0.1524)
				(type default)
			)
			(layer "F.SilkS")
		)
		(fp_rect
			(start -0.508 0.9398)
			(end 0.508 -0.9398)
			(stroke
				(width 0)
				(type default)
			)
			(fill no)
			(layer "F.CrtYd")
		)
		(fp_rect
			(start -0.508 0.9398)
			(end 0.508 -0.9398)
			(stroke
				(width 0)
				(type default)
			)
			(fill no)
			(layer "F.Fab")
		)
		(pad "1" smd custom
			(at 0 -0.4445 270)
			(size 0.1397 0.1397)
			(layers "F.Cu" "F.Mask" "F.Paste")
			(net "I2C_MUX_RESET")
			(options
				(clearance outline)
				(anchor circle)
			)
			(primitives
				(gr_poly
					(pts
						(arc
							(start -0.1778 -0.2794)
							(mid -0.249642 -0.249642)
							(end -0.2794 -0.1778)
						)
						(arc
							(start -0.2794 0.1778)
							(mid -0.249642 0.249642)
							(end -0.1778 0.2794)
						)
						(arc
							(start 0.1778 0.2794)
							(mid 0.249642 0.249642)
							(end 0.2794 0.1778)
						)
						(arc
							(start 0.2794 -0.1778)
							(mid 0.249642 -0.249642)
							(end 0.1778 -0.2794)
						)
					)
					(width 0)
					(fill yes)
				)
			)
		)
		(pad "2" smd custom
			(at 0 0.4445 270)
			(size 0.1397 0.1397)
			(layers "F.Cu" "F.Mask" "F.Paste")
			(net "I2C_MUX_RESET_R_EU16")
			(options
				(clearance outline)
				(anchor circle)
			)
			(primitives
				(gr_poly
					(pts
						(arc
							(start -0.1778 -0.2794)
							(mid -0.249642 -0.249642)
							(end -0.2794 -0.1778)
						)
						(arc
							(start -0.2794 0.1778)
							(mid -0.249642 0.249642)
							(end -0.1778 0.2794)
						)
						(arc
							(start 0.1778 0.2794)
							(mid 0.249642 0.249642)
							(end 0.2794 0.1778)
						)
						(arc
							(start 0.2794 -0.1778)
							(mid 0.249642 -0.249642)
							(end 0.1778 -0.2794)
						)
					)
					(width 0)
					(fill yes)
				)
			)
		)
	)
	(footprint ""
		(layer "F.Cu")
		(at 95.377 -198.755 90)
		(property "Reference" "C9341"
			(at 0 0 90)
			(layer "F.SilkS")
			(hide yes)
			(effects
				(font
					(size 1.27 1.27)
				)
			)
		)
		(property "Value" "SC1KP50V2KX-1GP"
			(at 1.1811 -2.7051 90)
			(unlocked yes)
			(layer "F.Fab")
			(hide yes)
			(effects
				(font
					(size 1.016 1.016)
					(thickness 0.1524)
				)
			)
		)
		(property "Device Type" "C402H22"
			(at 1.1811 -4.2291 90)
			(unlocked yes)
			(layer "F.Fab")
			(hide yes)
			(effects
				(font
					(size 1.016 1.016)
					(thickness 0.1524)
				)
			)
		)
		(duplicate_pad_numbers_are_jumpers no)
		(fp_rect
			(start -0.4318 0.9525)
			(end 0.4318 -0.9525)
			(stroke
				(width 0)
				(type default)
			)
			(fill no)
			(layer "F.CrtYd")
		)
		(fp_rect
			(start -0.4318 0.9525)
			(end 0.4318 -0.9525)
			(stroke
				(width 0)
				(type default)
			)
			(fill no)
			(layer "F.Fab")
		)
		(pad "1" smd custom
			(at 0 -0.4445 90)
			(size 0.1524 0.1524)
			(layers "F.Cu" "F.Mask" "F.Paste")
			(net "SSD_PRSNT4")
			(options
				(clearance outline)
				(anchor circle)
			)
			(primitives
				(gr_poly
					(pts
						(arc
							(start 0.3048 -0.2032)
							(mid 0.275042 -0.275042)
							(end 0.2032 -0.3048)
						)
						(arc
							(start -0.2032 -0.3048)
							(mid -0.275042 -0.275042)
							(end -0.3048 -0.2032)
						)
						(arc
							(start -0.3048 0.2032)
							(mid -0.275042 0.275042)
							(end -0.2032 0.3048)
						)
						(arc
							(start 0.2032 0.3048)
							(mid 0.275042 0.275042)
							(end 0.3048 0.2032)
						)
					)
					(width 0)
					(fill yes)
				)
			)
		)
		(pad "2" smd custom
			(at 0 0.4445 90)
			(size 0.1524 0.1524)
			(layers "F.Cu" "F.Mask" "F.Paste")
			(net "GND")
			(options
				(clearance outline)
				(anchor circle)
			)
			(primitives
				(gr_poly
					(pts
						(arc
							(start 0.3048 -0.2032)
							(mid 0.275042 -0.275042)
							(end 0.2032 -0.3048)
						)
						(arc
							(start -0.2032 -0.3048)
							(mid -0.275042 -0.275042)
							(end -0.3048 -0.2032)
						)
						(arc
							(start -0.3048 0.2032)
							(mid -0.275042 0.275042)
							(end -0.2032 0.3048)
						)
						(arc
							(start 0.2032 0.3048)
							(mid 0.275042 0.275042)
							(end 0.3048 0.2032)
						)
					)
					(width 0)
					(fill yes)
				)
			)
		)
	)
	(footprint ""
		(layer "F.Cu")
		(at 70.739 -356.489 90)
		(property "Reference" "SR1155"
			(at 0 0 90)
			(layer "F.SilkS")
			(hide yes)
			(effects
				(font
					(size 1.27 1.27)
				)
			)
		)
		(property "Value" "4K7R2F-GP"
			(at 0.064008 -3.993896 90)
			(unlocked yes)
			(layer "F.Fab")
			(hide yes)
			(effects
				(font
					(size 1.016 1.016)
					(thickness 0.1524)
				)
			)
		)
		(property "Device Type" "R402H16"
			(at 0.064008 -5.517896 90)
			(unlocked yes)
			(layer "F.Fab")
			(hide yes)
			(effects
				(font
					(size 1.016 1.016)
					(thickness 0.1524)
				)
			)
		)
		(duplicate_pad_numbers_are_jumpers no)
		(fp_line
			(start 0.508 -0.9398)
			(end -0.508 -0.9398)
			(stroke
				(width 0.1524)
				(type default)
			)
			(layer "F.SilkS")
		)
		(fp_line
			(start -0.508 -0.9398)
			(end -0.508 0.9398)
			(stroke
				(width 0.1524)
				(type default)
			)
			(layer "F.SilkS")
		)
		(fp_rect
			(start -0.508 0.9398)
			(end 0.508 -0.9398)
			(stroke
				(width 0)
				(type default)
			)
			(fill no)
			(layer "F.CrtYd")
		)
		(fp_rect
			(start -0.508 0.9398)
			(end 0.508 -0.9398)
			(stroke
				(width 0)
				(type default)
			)
			(fill no)
			(layer "F.Fab")
		)
		(pad "1" smd custom
			(at 0 -0.4445 90)
			(size 0.1397 0.1397)
			(layers "F.Cu" "F.Mask" "F.Paste")
			(net "P3V3")
			(options
				(clearance outline)
				(anchor circle)
			)
			(primitives
				(gr_poly
					(pts
						(arc
							(start -0.1778 -0.2794)
							(mid -0.249642 -0.249642)
							(end -0.2794 -0.1778)
						)
						(arc
							(start -0.2794 0.1778)
							(mid -0.249642 0.249642)
							(end -0.1778 0.2794)
						)
						(arc
							(start 0.1778 0.2794)
							(mid 0.249642 0.249642)
							(end 0.2794 0.1778)
						)
						(arc
							(start 0.2794 -0.1778)
							(mid 0.249642 -0.249642)
							(end 0.1778 -0.2794)
						)
					)
					(width 0)
					(fill yes)
				)
			)
		)
		(pad "2" smd custom
			(at 0 0.4445 90)
			(size 0.1397 0.1397)
			(layers "F.Cu" "F.Mask" "F.Paste")
			(net "I2C_SW_EU17_ADDRESS_A2")
			(options
				(clearance outline)
				(anchor circle)
			)
			(primitives
				(gr_poly
					(pts
						(arc
							(start -0.1778 -0.2794)
							(mid -0.249642 -0.249642)
							(end -0.2794 -0.1778)
						)
						(arc
							(start -0.2794 0.1778)
							(mid -0.249642 0.249642)
							(end -0.1778 0.2794)
						)
						(arc
							(start 0.1778 0.2794)
							(mid 0.249642 0.249642)
							(end 0.2794 0.1778)
						)
						(arc
							(start 0.2794 -0.1778)
							(mid 0.249642 -0.249642)
							(end 0.1778 -0.2794)
						)
					)
					(width 0)
					(fill yes)
				)
			)
		)
	)
	(footprint ""
		(layer "F.Cu")
		(at 32.2326 -211.0994 90)
		(property "Reference" "U21"
			(at 0 0 90)
			(layer "F.SilkS")
			(hide yes)
			(effects
				(font
					(size 1.27 1.27)
				)
			)
		)
		(property "Value" "P2003EVG-GP"
			(at 0 -11.1252 90)
			(unlocked yes)
			(layer "F.Fab")
			(hide yes)
			(effects
				(font
					(size 1.016 1.016)
					(thickness 0.1524)
				)
			)
		)
		(property "Device Type" "SOIC8H79"
			(at 0 -12.6492 90)
			(unlocked yes)
			(layer "F.Fab")
			(hide yes)
			(effects
				(font
					(size 1.016 1.016)
					(thickness 0.1524)
				)
			)
		)
		(duplicate_pad_numbers_are_jumpers no)
		(fp_line
			(start 2.1336 -1.4224)
			(end -2.7432 -1.4224)
			(stroke
				(width 0.1524)
				(type default)
			)
			(layer "F.SilkS")
		)
		(fp_line
			(start -2.7432 -1.4224)
			(end -2.7432 1.4224)
			(stroke
				(width 0.1524)
				(type default)
			)
			(layer "F.SilkS")
		)
		(fp_line
			(start -2.7432 -0.508)
			(end -2.2352 0)
			(stroke
				(width 0.1524)
				(type default)
			)
			(layer "F.SilkS")
		)
		(fp_line
			(start -2.2352 0)
			(end -2.7432 0.508)
			(stroke
				(width 0.1524)
				(type default)
			)
			(layer "F.SilkS")
		)
		(fp_line
			(start 2.1336 1.4224)
			(end 2.1336 -1.4224)
			(stroke
				(width 0.1524)
				(type default)
			)
			(layer "F.SilkS")
		)
		(fp_line
			(start -2.7432 1.4224)
			(end 2.1336 1.4224)
			(stroke
				(width 0.1524)
				(type default)
			)
			(layer "F.SilkS")
		)
		(fp_line
			(start -2.6162 3.429)
			(end -2.6162 1.4732)
			(stroke
				(width 0.4064)
				(type default)
			)
			(layer "F.SilkS")
		)
		(fp_poly
			(pts
				(xy 2.2098 -1.4224) (xy 2.2098 1.4224) (xy -2.2225 1.4224) (xy -2.2225 -1.4224)
			)
			(stroke
				(width 0)
				(type default)
			)
			(fill yes)
			(layer "F.SilkS")
		)
		(fp_rect
			(start -2.4511 2.9972)
			(end 2.4511 -2.9972)
			(stroke
				(width 0)
				(type default)
			)
			(fill no)
			(layer "F.CrtYd")
		)
		(fp_poly
			(pts
				(xy -2.8194 3.6322) (xy -2.8194 -3.6322) (xy 2.8194 -3.6322) (xy 2.8194 -2.2987) (xy 2.4511 -2.2987)
				(xy 2.4511 -2.9972) (xy -2.4511 -2.9972) (xy -2.4511 2.9972) (xy 2.4511 2.9972) (xy 2.4511 -2.286)
				(xy 2.8194 -2.286) (xy 2.8194 3.6322)
			)
			(stroke
				(width 0)
				(type default)
			)
			(fill no)
			(layer "F.CrtYd")
		)
		(fp_rect
			(start -2.8194 3.6322)
			(end 2.8194 -3.6322)
			(stroke
				(width 0)
				(type default)
			)
			(fill no)
			(layer "F.Fab")
		)
		(pad "1" smd rect
			(at -1.905 2.54 90)
			(size 0.635 1.651)
			(layers "F.Cu" "F.Mask" "F.Paste")
			(net "P12V")
		)
		(pad "2" smd rect
			(at -0.635 2.54 90)
			(size 0.635 1.651)
			(layers "F.Cu" "F.Mask" "F.Paste")
			(net "P12V")
		)
		(pad "3" smd rect
			(at 0.635 2.54 90)
			(size 0.635 1.651)
			(layers "F.Cu" "F.Mask" "F.Paste")
			(net "P12V")
		)
		(pad "4" smd rect
			(at 1.905 2.54 90)
			(size 0.635 1.651)
			(layers "F.Cu" "F.Mask" "F.Paste")
			(net "SW_SSD12_N")
		)
		(pad "5" smd rect
			(at 1.905 -2.54 90)
			(size 0.635 1.651)
			(layers "F.Cu" "F.Mask" "F.Paste")
			(net "P12V_SSD12")
		)
		(pad "6" smd rect
			(at 0.635 -2.54 90)
			(size 0.635 1.651)
			(layers "F.Cu" "F.Mask" "F.Paste")
			(net "P12V_SSD12")
		)
		(pad "7" smd rect
			(at -0.635 -2.54 90)
			(size 0.635 1.651)
			(layers "F.Cu" "F.Mask" "F.Paste")
			(net "P12V_SSD12")
		)
		(pad "8" smd rect
			(at -1.905 -2.54 90)
			(size 0.635 1.651)
			(layers "F.Cu" "F.Mask" "F.Paste")
			(net "P12V_SSD12")
		)
	)
	(footprint ""
		(layer "F.Cu")
		(at 209.677 -498.475 180)
		(property "Reference" "PC1186"
			(at 0 0 180)
			(layer "F.SilkS")
			(hide yes)
			(effects
				(font
					(size 1.27 1.27)
				)
			)
		)
		(property "Value" "SC22U25V6KX-GP-U"
			(at -2.860802 -5.279644 180)
			(unlocked yes)
			(layer "F.Fab")
			(hide yes)
			(effects
				(font
					(size 1.016 1.016)
					(thickness 0.1524)
				)
			)
		)
		(property "Device Type" "C1206-TO0D3H75"
			(at -2.860802 -6.803644 180)
			(unlocked yes)
			(layer "F.Fab")
			(hide yes)
			(effects
				(font
					(size 1.016 1.016)
					(thickness 0.1524)
				)
			)
		)
		(duplicate_pad_numbers_are_jumpers no)
		(fp_line
			(start 1.3081 2.3749)
			(end -1.3081 2.3749)
			(stroke
				(width 0.1524)
				(type default)
			)
			(layer "F.SilkS")
		)
		(fp_line
			(start 1.3081 -2.3749)
			(end 1.3081 2.3749)
			(stroke
				(width 0.1524)
				(type default)
			)
			(layer "F.SilkS")
		)
		(fp_line
			(start -1.3081 2.3749)
			(end -1.3081 -2.3749)
			(stroke
				(width 0.1524)
				(type default)
			)
			(layer "F.SilkS")
		)
		(fp_line
			(start -1.3081 -2.3749)
			(end 1.3081 -2.3749)
			(stroke
				(width 0.1524)
				(type default)
			)
			(layer "F.SilkS")
		)
		(fp_rect
			(start -0.8001 1.6002)
			(end 0.8001 -1.6002)
			(stroke
				(width 0)
				(type default)
			)
			(fill no)
			(layer "F.CrtYd")
		)
		(fp_poly
			(pts
				(xy -1.5621 2.4511) (xy -1.5621 1.6002) (xy 0.8001 1.6002) (xy 0.8001 -1.6002) (xy -0.8001 -1.6002)
				(xy -0.8001 1.5875) (xy -1.5621 1.5875) (xy -1.5621 -2.4511) (xy 1.5621 -2.4511) (xy 1.5621 2.4511)
			)
			(stroke
				(width 0)
				(type default)
			)
			(fill no)
			(layer "F.CrtYd")
		)
		(fp_rect
			(start -1.5621 2.4511)
			(end 1.5621 -2.4511)
			(stroke
				(width 0)
				(type default)
			)
			(fill no)
			(layer "F.Fab")
		)
		(pad "1" smd rect
			(at 0 -1.392936 180)
			(size 2.1082 1.4478)
			(layers "F.Cu" "F.Mask" "F.Paste")
			(net "P12V_SSD0")
		)
		(pad "2" smd rect
			(at 0 1.392936 180)
			(size 2.1082 1.4478)
			(layers "F.Cu" "F.Mask" "F.Paste")
			(net "GND")
		)
	)
	(footprint ""
		(layer "F.Cu")
		(at 214.3887 -84.455)
		(property "Reference" "SR1099"
			(at 0 0 0)
			(layer "F.SilkS")
			(hide yes)
			(effects
				(font
					(size 1.27 1.27)
				)
			)
		)
		(property "Value" "4K7R2F-GP"
			(at 0.064008 -3.993896 0)
			(unlocked yes)
			(layer "F.Fab")
			(hide yes)
			(effects
				(font
					(size 1.016 1.016)
					(thickness 0.1524)
				)
			)
		)
		(property "Device Type" "R402H16"
			(at 0.064008 -5.517896 0)
			(unlocked yes)
			(layer "F.Fab")
			(hide yes)
			(effects
				(font
					(size 1.016 1.016)
					(thickness 0.1524)
				)
			)
		)
		(duplicate_pad_numbers_are_jumpers no)
		(fp_line
			(start -0.508 -0.9398)
			(end -0.508 0.9398)
			(stroke
				(width 0.1524)
				(type default)
			)
			(layer "F.SilkS")
		)
		(fp_line
			(start 0.508 -0.9398)
			(end -0.508 -0.9398)
			(stroke
				(width 0.1524)
				(type default)
			)
			(layer "F.SilkS")
		)
		(fp_rect
			(start -0.508 0.9398)
			(end 0.508 -0.9398)
			(stroke
				(width 0)
				(type default)
			)
			(fill no)
			(layer "F.CrtYd")
		)
		(fp_rect
			(start -0.508 0.9398)
			(end 0.508 -0.9398)
			(stroke
				(width 0)
				(type default)
			)
			(fill no)
			(layer "F.Fab")
		)
		(pad "1" smd custom
			(at 0 -0.4445)
			(size 0.1397 0.1397)
			(layers "F.Cu" "F.Mask" "F.Paste")
			(net "P3V3")
			(options
				(clearance outline)
				(anchor circle)
			)
			(primitives
				(gr_poly
					(pts
						(arc
							(start -0.1778 -0.2794)
							(mid -0.249642 -0.249642)
							(end -0.2794 -0.1778)
						)
						(arc
							(start -0.2794 0.1778)
							(mid -0.249642 0.249642)
							(end -0.1778 0.2794)
						)
						(arc
							(start 0.1778 0.2794)
							(mid 0.249642 0.249642)
							(end 0.2794 0.1778)
						)
						(arc
							(start 0.2794 -0.1778)
							(mid 0.249642 -0.249642)
							(end 0.1778 -0.2794)
						)
					)
					(width 0)
					(fill yes)
				)
			)
		)
		(pad "2" smd custom
			(at 0 0.4445)
			(size 0.1397 0.1397)
			(layers "F.Cu" "F.Mask" "F.Paste")
			(net "DUALPORTEN#4")
			(options
				(clearance outline)
				(anchor circle)
			)
			(primitives
				(gr_poly
					(pts
						(arc
							(start -0.1778 -0.2794)
							(mid -0.249642 -0.249642)
							(end -0.2794 -0.1778)
						)
						(arc
							(start -0.2794 0.1778)
							(mid -0.249642 0.249642)
							(end -0.1778 0.2794)
						)
						(arc
							(start 0.1778 0.2794)
							(mid 0.249642 0.249642)
							(end 0.2794 0.1778)
						)
						(arc
							(start 0.2794 -0.1778)
							(mid 0.249642 -0.249642)
							(end 0.1778 -0.2794)
						)
					)
					(width 0)
					(fill yes)
				)
			)
		)
	)
)
